# S9S_MB_2U (Grand Teton) — schematic netlist excerpt (pin names and nets, part order shuffled) for the footprints in the layout excerpt that follows; sources: Cadence DE-HDL packaged netlist, KiCad conversion of 03242023_DA0F0TMBIJ0_F0T_Motherboard_J_brd_V01_OCP.brd

J26  SCONN288_ADR50017P087CC  SCONN288_ADR50017-P087CC IO  pkg DDR288S_1-1VXB  page 107
  VIN_BULK0  = P12V_S3_AUX_CPU1_NVDIMM
  RFU0  = TP_CHE_CPU1_DIMM2_FRU_0
  VIN_MGMT  = P3V3_AUX
  HSCL  = I3C_SPD_DDREFGH_CPU1_LVC1_SCL_1
  HSDA  = I3C_SPD_DDREFGH_CPU1_LVC1_SDA
  VSS0  = GND
  DQ0_A  = M_E_CPU1_SA_DQ<0>
  VSS1  = GND
  DQ1_A  = M_E_CPU1_SA_DQ<1>
  VSS2  = GND
  DQS0_A_T  = M_E_CPU1_SA_DQS_DP<0>
  DQS0_A_C  = M_E_CPU1_SA_DQS_DN<0>
  VSS3  = GND
  DQ4_A  = M_E_CPU1_SA_DQ<4>
  VSS4  = GND
  DQ5_A  = M_E_CPU1_SA_DQ<5>
  VSS5  = GND
  DQ8_A  = M_E_CPU1_SA_DQ<8>
  VSS6  = GND
  DQ9_A  = M_E_CPU1_SA_DQ<9>
  VSS7  = GND
  DQS1_A_T  = M_E_CPU1_SA_DQS_DP<1>
  DQS1_A_C  = M_E_CPU1_SA_DQS_DN<1>
  VSS8  = GND
  DQ12_A  = M_E_CPU1_SA_DQ<12>
  VSS9  = GND
  DQ13_A  = M_E_CPU1_SA_DQ<13>
  VSS10  = GND
  DQ16_A  = M_E_CPU1_SA_DQ<16>
  VSS11  = GND
  DQ17_A  = M_E_CPU1_SA_DQ<17>
  VSS12  = GND
  DQS2_A_T  = M_E_CPU1_SA_DQS_DP<2>
  DQS2_A_C  = M_E_CPU1_SA_DQS_DN<2>
  VSS13  = GND
  DQ20_A  = M_E_CPU1_SA_DQ<20>
  VSS14  = GND
  DQ21_A  = M_E_CPU1_SA_DQ<21>
  VSS15  = GND
  DQ24_A  = M_E_CPU1_SA_DQ<24>
  VSS16  = GND
  DQ25_A  = M_E_CPU1_SA_DQ<25>
  VSS17  = GND
  DQS3_A_T  = M_E_CPU1_SA_DQS_DP<3>
  DQS3_A_C  = M_E_CPU1_SA_DQS_DN<3>
  VSS18  = GND
  DQ28_A  = M_E_CPU1_SA_DQ<28>
  VSS19  = GND
  DQ29_A  = M_E_CPU1_SA_DQ<29>
  VSS20  = GND
  CB0_A  = M_E_CPU1_SA_CB<0>
  VSS21  = GND
  CB1_A  = M_E_CPU1_SA_CB<1>
  VSS22  = GND
  DQS4_A_T  = M_E_CPU1_SA_DQS_DP<4>
  DQS4_A_C  = M_E_CPU1_SA_DQS_DN<4>
  VSS23  = GND
  CB4_A  = M_E_CPU1_SA_CB<4>
  VSS24  = GND
  CB5_A  = M_E_CPU1_SA_CB<5>
  VSS25  = GND
  ALERT_N  = M_E_CPU1_ALERT_N
  VSS26  = GND
  CS0_A_N  = M_E_CPU1_SA_CS_N<2>
  VSS27  = GND
  CA0_A  = M_E_CPU1_SA_CA<0>
  VSS28  = GND
  CA2_A  = M_E_CPU1_SA_CA<2>
  VSS29  = GND
  CA4_A  = M_E_CPU1_SA_CA<4>
  VSS30  = GND
  CA6_A  = M_E_CPU1_SA_CA<6>
  VSS31  = GND
  PAR_A  = M_E_CPU1_SA_PAR
  VSS32  = GND
  CA0_B  = M_E_CPU1_SB_CA<0>
  VSS33  = GND
  CA2_B  = M_E_CPU1_SB_CA<2>
  VSS34  = GND
  CA4_B  = M_E_CPU1_SB_CA<4>
  VSS35  = GND
  CA6_B  = M_E_CPU1_SB_CA<6>
  VSS36  = GND
  CS0_B_N  = M_E_CPU1_SB_CS_N<2>
  VSS37  = GND
  \lbd||rsp_a_n\  = M_E_CPU1_SA_RSP<1>
  \lbs||rsp_b_n\  = M_E_CPU1_SB_RSP<1>
  VSS38  = GND
  CB4_B  = M_E_CPU1_SB_CB<4>
  VSS39  = GND
  CB5_B  = M_E_CPU1_SB_CB<5>
  VSS40  = GND
  \dqs9_b_t||tdqs9_b_t||dbi4_b_n\  = M_E_CPU1_SB_DQS_DP<9>
  \dqs9_b_c||tdqs9_b_c\  = M_E_CPU1_SB_DQS_DN<9>
  VSS41  = GND
  CB0_B  = M_E_CPU1_SB_CB<0>
  VSS42  = GND
  CB1_B  = M_E_CPU1_SB_CB<1>
  VSS43  = GND
  DQ0_B  = M_E_CPU1_SB_DQ<0>
  VSS44  = GND
  DQ1_B  = M_E_CPU1_SB_DQ<1>
  VSS45  = GND
  DQS0_B_T  = M_E_CPU1_SB_DQS_DP<0>
  DQS0_B_C  = M_E_CPU1_SB_DQS_DN<0>
  VSS46  = GND
  DQ4_B  = M_E_CPU1_SB_DQ<4>
  VSS47  = GND
  DQ5_B  = M_E_CPU1_SB_DQ<5>
  VSS48  = GND
  DQ8_B  = M_E_CPU1_SB_DQ<8>
  VSS49  = GND
  DQ9_B  = M_E_CPU1_SB_DQ<9>
  VSS50  = GND
  DQS1_B_T  = M_E_CPU1_SB_DQS_DP<1>
  DQS1_B_C  = M_E_CPU1_SB_DQS_DN<1>
  VSS51  = GND
  DQ12_B  = M_E_CPU1_SB_DQ<12>
  VSS52  = GND
  DQ13_B  = M_E_CPU1_SB_DQ<13>
  VSS53  = GND
  DQ16_B  = M_E_CPU1_SB_DQ<16>
  VSS54  = GND
  DQ17_B  = M_E_CPU1_SB_DQ<17>
  VSS55  = GND
  DQS2_B_T  = M_E_CPU1_SB_DQS_DP<2>
  DQS2_B_C  = M_E_CPU1_SB_DQS_DN<2>
  VSS56  = GND
  DQ20_B  = M_E_CPU1_SB_DQ<20>
  VSS57  = GND
  DQ21_B  = M_E_CPU1_SB_DQ<21>
  VSS58  = GND
  DQ24_B  = M_E_CPU1_SB_DQ<24>
  VSS59  = GND
  DQ25_B  = M_E_CPU1_SB_DQ<25>
  VSS60  = GND
  DQS3_B_T  = M_E_CPU1_SB_DQS_DP<3>
  DQS3_B_C  = M_E_CPU1_SB_DQS_DN<3>
  VSS61  = GND
  DQ28_B  = M_E_CPU1_SB_DQ<28>
  VSS62  = GND
  DQ29_B  = M_E_CPU1_SB_DQ<29>
  VSS63  = GND
  RFU1  = TP_CHE_CPU1_DIMM2_FRU_1
  VIN_BULK1  = P12V_S3_AUX_CPU1_NVDIMM
  VIN_BULK2  = P12V_S3_AUX_CPU1_NVDIMM
  \pwr_good||fail_n\  = PWRGD_CHE_CPU1_DIMM2
  HSA  = PD_CHE_CPU1_DIMM2_SAA
  RFU2  = TP_CHE_CPU1_DIMM2_FRU_2
  RFU3  = TP_CHE_CPU1_DIMM2_FRU_3
  VSS64  = GND
  DQ2_A  = M_E_CPU1_SA_DQ<2>
  VSS65  = GND
  DQ3_A  = M_E_CPU1_SA_DQ<3>
  VSS66  = GND
  \dqs5_a_c||tdqs5_a_c||dqs5_a_t||tdqs5_a_t\  = M_E_CPU1_SA_DQS_DN<5>
  \dqs5_a_t||tdqs5_a_t\  = M_E_CPU1_SA_DQS_DP<5>
  VSS67  = GND
  DQ6_A  = M_E_CPU1_SA_DQ<6>
  VSS68  = GND
  DQ7_A  = M_E_CPU1_SA_DQ<7>
  VSS69  = GND
  DQ10_A  = M_E_CPU1_SA_DQ<10>
  VSS70  = GND
  DQ11_A  = M_E_CPU1_SA_DQ<11>
  VSS71  = GND
  \dqs6_a_c||tdqs6_a_c||dqs6_a_t||tdqs6_a_t\  = M_E_CPU1_SA_DQS_DN<6>
  \dqs6_a_t||tdqs6_a_t\  = M_E_CPU1_SA_DQS_DP<6>
  VSS72  = GND
  DQ14_A  = M_E_CPU1_SA_DQ<14>
  VSS73  = GND
  DQ15_A  = M_E_CPU1_SA_DQ<15>
  VSS74  = GND
  DQ18_A  = M_E_CPU1_SA_DQ<18>
  VSS75  = GND
  DQ19_A  = M_E_CPU1_SA_DQ<19>
  VSS76  = GND
  \dqs7_a_c||tdqs7_a_c\  = M_E_CPU1_SA_DQS_DN<7>
  \dqs7_a_t||tdqs7_a_t\  = M_E_CPU1_SA_DQS_DP<7>
  VSS77  = GND
  DQ22_A  = M_E_CPU1_SA_DQ<22>
  VSS78  = GND
  DQ23_A  = M_E_CPU1_SA_DQ<23>
  VSS79  = GND
  DQ26_A  = M_E_CPU1_SA_DQ<26>
  VSS80  = GND
  DQ27_A  = M_E_CPU1_SA_DQ<27>
  VSS81  = GND
  \dqs8_a_c||tdqs8_a_c\  = M_E_CPU1_SA_DQS_DN<8>
  \dqs8_a_t||tdqs8_a_t\  = M_E_CPU1_SA_DQS_DP<8>
  VSS82  = GND
  DQ30_A  = M_E_CPU1_SA_DQ<30>
  VSS83  = GND
  DQ31_A  = M_E_CPU1_SA_DQ<31>
  VSS84  = GND
  CB2_A  = M_E_CPU1_SA_CB<2>
  VSS85  = GND
  CB3_A  = M_E_CPU1_SA_CB<3>
  VSS86  = GND
  \dqs9_a_c||tdqs9_a_c\  = M_E_CPU1_SA_DQS_DN<9>
  \dqs9_a_t||tdqs9_a_t\  = M_E_CPU1_SA_DQS_DP<9>
  VSS87  = GND
  CB6_A  = M_E_CPU1_SA_CB<6>
  VSS88  = GND
  CB7_A  = M_E_CPU1_SA_CB<7>
  VSS89  = GND
  RESET_N  = RST_M_EF_CPU1_FPGA_N
  VSS90  = GND
  CS1_A_N  = M_E_CPU1_SA_CS_N<3>
  VSS91  = GND
  CA1_A  = M_E_CPU1_SA_CA<1>
  VSS92  = GND
  CA3_A  = M_E_CPU1_SA_CA<3>
  VSS93  = GND
  CA5_A  = M_E_CPU1_SA_CA<5>
  VSS94  = GND
  CK_T  = M_E_CPU1_CLK_DP<1>
  CK_C  = M_E_CPU1_CLK_DN<1>
  VSS95  = GND
  RFU4  = TP_CHE_CPU1_DIMM2_FRU_4
  CA1_B  = M_E_CPU1_SB_CA<1>
  VSS96  = GND
  CA3_B  = M_E_CPU1_SB_CA<3>
  VSS97  = GND
  CA5_B  = M_E_CPU1_SB_CA<5>
  VSS98  = GND
  PAR_B  = M_E_CPU1_SB_PAR
  VSS99  = GND
  CS1_B_N  = M_E_CPU1_SB_CS_N<3>
  VSS100  = GND
  RFU5  = TP_CHE_CPU1_DIMM2_FRU_5
  RFU6  = TP_CHE_CPU1_DIMM2_FRU_6
  VSS101  = GND
  CB6_B  = M_E_CPU1_SB_CB<6>
  VSS102  = GND
  CB7_B  = M_E_CPU1_SB_CB<7>
  VSS103  = GND
  DQS4_B_C  = M_E_CPU1_SB_DQS_DN<4>
  DQS4_B_T  = M_E_CPU1_SB_DQS_DP<4>
  VSS104  = GND
  CB2_B  = M_E_CPU1_SB_CB<2>
  VSS105  = GND
  CB3_B  = M_E_CPU1_SB_CB<3>
  VSS106  = GND
  DQ2_B  = M_E_CPU1_SB_DQ<2>
  VSS107  = GND
  DQ3_B  = M_E_CPU1_SB_DQ<3>
  VSS108  = GND
  \dqs5_b_c||tdqs5_b_c\  = M_E_CPU1_SB_DQS_DN<5>
  \dqs5_b_t||tdqs5_b_t\  = M_E_CPU1_SB_DQS_DP<5>
  VSS109  = GND
  DQ6_B  = M_E_CPU1_SB_DQ<6>
  VSS110  = GND
  DQ7_B  = M_E_CPU1_SB_DQ<7>
  VSS111  = GND
  DQ10_B  = M_E_CPU1_SB_DQ<10>
  VSS112  = GND
  DQ11_B  = M_E_CPU1_SB_DQ<11>
  VSS113  = GND
  \dqs6_b_c||tdqs6_b_c\  = M_E_CPU1_SB_DQS_DN<6>
  \dqs6_b_t||tdqs6_b_t\  = M_E_CPU1_SB_DQS_DP<6>
  VSS114  = GND
  DQ14_B  = M_E_CPU1_SB_DQ<14>
  VSS115  = GND
  DQ15_B  = M_E_CPU1_SB_DQ<15>
  VSS116  = GND
  DQ18_B  = M_E_CPU1_SB_DQ<18>
  VSS117  = GND
  DQ19_B  = M_E_CPU1_SB_DQ<19>
  VSS118  = GND
  \dqs7_b_c||tdqs7_b_c\  = M_E_CPU1_SB_DQS_DN<7>
  \dqs7_b_t||tdqs7_b_t\  = M_E_CPU1_SB_DQS_DP<7>
  VSS119  = GND
  DQ22_B  = M_E_CPU1_SB_DQ<22>
  VSS120  = GND
  DQ23_B  = M_E_CPU1_SB_DQ<23>
  VSS121  = GND
  DQ26_B  = M_E_CPU1_SB_DQ<26>
  VSS122  = GND
  DQ27_B  = M_E_CPU1_SB_DQ<27>
  VSS123  = GND
  \dqs8_b_c||tdqs8_b_c\  = M_E_CPU1_SB_DQS_DN<8>
  \dqs8_b_t||tdqs8_b_t\  = M_E_CPU1_SB_DQS_DP<8>
  VSS124  = GND
  DQ30_B  = M_E_CPU1_SB_DQ<30>
  VSS125  = GND
  DQ31_B  = M_E_CPU1_SB_DQ<31>
  VSS126  = GND
  G1  = GND
  G2  = GND
  G3  = GND

(kicad_pcb
	(version 20260206)
	(generator "pcbnew")
	(generator_version "10.0")
	(general
		(thickness 1.6)
		(legacy_teardrops no)
	)
	(paper "A4")
	(title_block
		(title "03242023_DA0F0TMBIJ0_F0T_Motherboard_J_brd_V01_OCP.brd")
		(comment 1 "Grand Teton / footprint 1065 of 6105 (J26), pads 229-274 of 291")
	)
	(layers
		(0 "F.Cu" signal "TOP")
		(4 "In1.Cu" signal "GND")
		(6 "In2.Cu" signal "IN1")
		(8 "In3.Cu" signal "GND1")
		(10 "In4.Cu" signal "IN2")
		(12 "In5.Cu" signal "GND2")
		(14 "In6.Cu" signal "IN3")
		(16 "In7.Cu" signal "GND3")
		(18 "In8.Cu" signal "VCC")
		(20 "In9.Cu" signal "VCC1")
		(22 "In10.Cu" signal "GND4")
		(24 "In11.Cu" signal "IN4")
		(26 "In12.Cu" signal "GND5")
		(28 "In13.Cu" signal "IN5")
		(30 "In14.Cu" signal "GND6")
		(32 "In15.Cu" signal "IN6")
		(34 "In16.Cu" signal "GND7")
		(2 "B.Cu" signal "BOTTOM")
		(9 "F.Adhes" user "F.Adhesive")
		(11 "B.Adhes" user "B.Adhesive")
		(13 "F.Paste" user "Package Geometry/Pastemask Top")
		(15 "B.Paste" user "Package Geometry/Pastemask Bottom")
		(5 "F.SilkS" user "Ref Des/Silkscreen Top")
		(7 "B.SilkS" user "Ref Des/Silkscreen Bottom")
		(1 "F.Mask" user "Board Geometry/Soldermask Top")
		(3 "B.Mask" user "Board Geometry/Soldermask Bottom")
		(17 "Dwgs.User" user "User.Drawings")
		(19 "Cmts.User" user "User.Comments")
		(21 "Eco1.User" user "User.Eco1")
		(23 "Eco2.User" user "User.Eco2")
		(25 "Edge.Cuts" user "Board Geometry/Outline")
		(27 "Margin" user)
		(31 "F.CrtYd" user "Package Geometry/Place Bound Top")
		(29 "B.CrtYd" user "Package Geometry/Place Bound Bottom")
		(35 "F.Fab" user "Ref Des/Assembly Top")
		(33 "B.Fab" user "Ref Des/Assembly Bottom")
	)
	(footprint ""
		(layer "F.Cu")
		(at 160.86328 -258.091686)
		(property "Reference" "J26"
			(at -3.683 -81.702148 0)
			(unlocked yes)
			(layer "F.SilkS")
			(effects
				(font
					(size 0.7874 0.5842)
					(thickness 0.1524)
				)
				(justify left)
			)
		)
		(property "Value" ""
			(at 0 0 0)
			(layer "F.Fab")
			(effects
				(font
					(size 1.27 1.27)
				)
			)
		)
		(duplicate_pad_numbers_are_jumpers no)
		(pad "229" smd rect
			(at 2.050034 13.17498 270)
			(size 0.519938 1.4986)
			(layers "F.Cu" "F.Mask" "F.Paste")
			(net "M_E_CPU1_SB_CS_N<3>")
		)
		(pad "230" smd rect
			(at 2.050034 14.025118 270)
			(size 0.519938 1.4986)
			(layers "F.Cu" "F.Mask" "F.Paste")
			(net "GND")
		)
		(pad "231" smd rect
			(at 2.050034 14.875002 270)
			(size 0.519938 1.4986)
			(layers "F.Cu" "F.Mask" "F.Paste")
			(net "TP_CHE_CPU1_DIMM2_FRU_5")
		)
		(pad "232" smd rect
			(at 2.050034 15.724886 270)
			(size 0.519938 1.4986)
			(layers "F.Cu" "F.Mask" "F.Paste")
			(net "TP_CHE_CPU1_DIMM2_FRU_6")
		)
		(pad "233" smd rect
			(at 2.050034 16.575024 270)
			(size 0.519938 1.4986)
			(layers "F.Cu" "F.Mask" "F.Paste")
			(net "GND")
		)
		(pad "234" smd rect
			(at 2.050034 17.424908 270)
			(size 0.519938 1.4986)
			(layers "F.Cu" "F.Mask" "F.Paste")
			(net "M_E_CPU1_SB_CB<6>")
		)
		(pad "235" smd rect
			(at 2.050034 18.275046 270)
			(size 0.519938 1.4986)
			(layers "F.Cu" "F.Mask" "F.Paste")
			(net "GND")
		)
		(pad "236" smd rect
			(at 2.050034 19.12493 270)
			(size 0.519938 1.4986)
			(layers "F.Cu" "F.Mask" "F.Paste")
			(net "M_E_CPU1_SB_CB<7>")
		)
		(pad "237" smd rect
			(at 2.050034 19.975068 270)
			(size 0.519938 1.4986)
			(layers "F.Cu" "F.Mask" "F.Paste")
			(net "GND")
		)
		(pad "238" smd rect
			(at 2.050034 20.824952 270)
			(size 0.519938 1.4986)
			(layers "F.Cu" "F.Mask" "F.Paste")
			(net "M_E_CPU1_SB_DQS_DN<4>")
		)
		(pad "239" smd rect
			(at 2.050034 21.67509 270)
			(size 0.519938 1.4986)
			(layers "F.Cu" "F.Mask" "F.Paste")
			(net "M_E_CPU1_SB_DQS_DP<4>")
		)
		(pad "240" smd rect
			(at 2.050034 22.524974 270)
			(size 0.519938 1.4986)
			(layers "F.Cu" "F.Mask" "F.Paste")
			(net "GND")
		)
		(pad "241" smd rect
			(at 2.050034 23.375112 270)
			(size 0.519938 1.4986)
			(layers "F.Cu" "F.Mask" "F.Paste")
			(net "M_E_CPU1_SB_CB<2>")
		)
		(pad "242" smd rect
			(at 2.050034 24.224996 270)
			(size 0.519938 1.4986)
			(layers "F.Cu" "F.Mask" "F.Paste")
			(net "GND")
		)
		(pad "243" smd rect
			(at 2.050034 25.07488 270)
			(size 0.519938 1.4986)
			(layers "F.Cu" "F.Mask" "F.Paste")
			(net "M_E_CPU1_SB_CB<3>")
		)
		(pad "244" smd rect
			(at 2.050034 25.925018 270)
			(size 0.519938 1.4986)
			(layers "F.Cu" "F.Mask" "F.Paste")
			(net "GND")
		)
		(pad "245" smd rect
			(at 2.050034 26.774902 270)
			(size 0.519938 1.4986)
			(layers "F.Cu" "F.Mask" "F.Paste")
			(net "M_E_CPU1_SB_DQ<2>")
		)
		(pad "246" smd rect
			(at 2.050034 27.62504 270)
			(size 0.519938 1.4986)
			(layers "F.Cu" "F.Mask" "F.Paste")
			(net "GND")
		)
		(pad "247" smd rect
			(at 2.050034 28.474924 270)
			(size 0.519938 1.4986)
			(layers "F.Cu" "F.Mask" "F.Paste")
			(net "M_E_CPU1_SB_DQ<3>")
		)
		(pad "248" smd rect
			(at 2.050034 29.325062 270)
			(size 0.519938 1.4986)
			(layers "F.Cu" "F.Mask" "F.Paste")
			(net "GND")
		)
		(pad "249" smd rect
			(at 2.050034 30.174946 270)
			(size 0.519938 1.4986)
			(layers "F.Cu" "F.Mask" "F.Paste")
			(net "M_E_CPU1_SB_DQS_DN<5>")
		)
		(pad "250" smd rect
			(at 2.050034 31.025084 270)
			(size 0.519938 1.4986)
			(layers "F.Cu" "F.Mask" "F.Paste")
			(net "M_E_CPU1_SB_DQS_DP<5>")
		)
		(pad "251" smd rect
			(at 2.050034 31.874968 270)
			(size 0.519938 1.4986)
			(layers "F.Cu" "F.Mask" "F.Paste")
			(net "GND")
		)
		(pad "252" smd rect
			(at 2.050034 32.725106 270)
			(size 0.519938 1.4986)
			(layers "F.Cu" "F.Mask" "F.Paste")
			(net "M_E_CPU1_SB_DQ<6>")
		)
		(pad "253" smd rect
			(at 2.050034 33.57499 270)
			(size 0.519938 1.4986)
			(layers "F.Cu" "F.Mask" "F.Paste")
			(net "GND")
		)
		(pad "254" smd rect
			(at 2.050034 34.425128 270)
			(size 0.519938 1.4986)
			(layers "F.Cu" "F.Mask" "F.Paste")
			(net "M_E_CPU1_SB_DQ<7>")
		)
		(pad "255" smd rect
			(at 2.050034 35.275012 270)
			(size 0.519938 1.4986)
			(layers "F.Cu" "F.Mask" "F.Paste")
			(net "GND")
		)
		(pad "256" smd rect
			(at 2.050034 36.124896 270)
			(size 0.519938 1.4986)
			(layers "F.Cu" "F.Mask" "F.Paste")
			(net "M_E_CPU1_SB_DQ<10>")
		)
		(pad "257" smd rect
			(at 2.050034 36.975034 270)
			(size 0.519938 1.4986)
			(layers "F.Cu" "F.Mask" "F.Paste")
			(net "GND")
		)
		(pad "258" smd rect
			(at 2.050034 37.824918 270)
			(size 0.519938 1.4986)
			(layers "F.Cu" "F.Mask" "F.Paste")
			(net "M_E_CPU1_SB_DQ<11>")
		)
		(pad "259" smd rect
			(at 2.050034 38.675056 270)
			(size 0.519938 1.4986)
			(layers "F.Cu" "F.Mask" "F.Paste")
			(net "GND")
		)
		(pad "260" smd rect
			(at 2.050034 39.52494 270)
			(size 0.519938 1.4986)
			(layers "F.Cu" "F.Mask" "F.Paste")
			(net "M_E_CPU1_SB_DQS_DN<6>")
		)
		(pad "261" smd rect
			(at 2.050034 40.375078 270)
			(size 0.519938 1.4986)
			(layers "F.Cu" "F.Mask" "F.Paste")
			(net "M_E_CPU1_SB_DQS_DP<6>")
		)
		(pad "262" smd rect
			(at 2.050034 41.224962 270)
			(size 0.519938 1.4986)
			(layers "F.Cu" "F.Mask" "F.Paste")
			(net "GND")
		)
		(pad "263" smd rect
			(at 2.050034 42.0751 270)
			(size 0.519938 1.4986)
			(layers "F.Cu" "F.Mask" "F.Paste")
			(net "M_E_CPU1_SB_DQ<14>")
		)
		(pad "264" smd rect
			(at 2.050034 42.924984 270)
			(size 0.519938 1.4986)
			(layers "F.Cu" "F.Mask" "F.Paste")
			(net "GND")
		)
		(pad "265" smd rect
			(at 2.050034 43.775122 270)
			(size 0.519938 1.4986)
			(layers "F.Cu" "F.Mask" "F.Paste")
			(net "M_E_CPU1_SB_DQ<15>")
		)
		(pad "266" smd rect
			(at 2.050034 44.625006 270)
			(size 0.519938 1.4986)
			(layers "F.Cu" "F.Mask" "F.Paste")
			(net "GND")
		)
		(pad "267" smd rect
			(at 2.050034 45.47489 270)
			(size 0.519938 1.4986)
			(layers "F.Cu" "F.Mask" "F.Paste")
			(net "M_E_CPU1_SB_DQ<18>")
		)
		(pad "268" smd rect
			(at 2.050034 46.325028 270)
			(size 0.519938 1.4986)
			(layers "F.Cu" "F.Mask" "F.Paste")
			(net "GND")
		)
		(pad "269" smd rect
			(at 2.050034 47.174912 270)
			(size 0.519938 1.4986)
			(layers "F.Cu" "F.Mask" "F.Paste")
			(net "M_E_CPU1_SB_DQ<19>")
		)
		(pad "270" smd rect
			(at 2.050034 48.02505 270)
			(size 0.519938 1.4986)
			(layers "F.Cu" "F.Mask" "F.Paste")
			(net "GND")
		)
		(pad "271" smd rect
			(at 2.050034 48.874934 270)
			(size 0.519938 1.4986)
			(layers "F.Cu" "F.Mask" "F.Paste")
			(net "M_E_CPU1_SB_DQS_DN<7>")
		)
		(pad "272" smd rect
			(at 2.050034 49.725072 270)
			(size 0.519938 1.4986)
			(layers "F.Cu" "F.Mask" "F.Paste")
			(net "M_E_CPU1_SB_DQS_DP<7>")
		)
		(pad "273" smd rect
			(at 2.050034 50.574956 270)
			(size 0.519938 1.4986)
			(layers "F.Cu" "F.Mask" "F.Paste")
			(net "GND")
		)
		(pad "274" smd rect
			(at 2.050034 51.425094 270)
			(size 0.519938 1.4986)
			(layers "F.Cu" "F.Mask" "F.Paste")
			(net "M_E_CPU1_SB_DQ<22>")
		)
	)
)
